(kicad_pcb
	(version 20260206)
	(generator "pcbnew")
	(generator_version "10.0")
	(general
		(thickness 1.6)
		(legacy_teardrops no)
	)
	(paper "A4")
	(title_block
		(title "4HDD Backplane_Layout.brd")
		(comment 1 "Tioga Pass / footprints 17-24 of 97")
	)
	(layers
		(0 "F.Cu" signal "TOP")
		(4 "In1.Cu" signal "L2GND")
		(6 "In2.Cu" signal "L3")
		(8 "In3.Cu" signal "L4")
		(10 "In4.Cu" signal "L5GND")
		(2 "B.Cu" signal "BOTTOM")
		(9 "F.Adhes" user "F.Adhesive")
		(11 "B.Adhes" user "B.Adhesive")
		(13 "F.Paste" user "Package Geometry/Pastemask Top")
		(15 "B.Paste" user "Package Geometry/Pastemask Bottom")
		(5 "F.SilkS" user "Ref Des/Silkscreen Top")
		(7 "B.SilkS" user "Ref Des/Silkscreen Bottom")
		(1 "F.Mask" user "Board Geometry/Soldermask Top")
		(3 "B.Mask" user "Board Geometry/Soldermask Bottom")
		(17 "Dwgs.User" user "User.Drawings")
		(19 "Cmts.User" user "User.Comments")
		(21 "Eco1.User" user "User.Eco1")
		(23 "Eco2.User" user "User.Eco2")
		(25 "Edge.Cuts" user "Board Geometry/Outline")
		(27 "Margin" user)
		(31 "F.CrtYd" user "Package Geometry/Place Bound Top")
		(29 "B.CrtYd" user "Package Geometry/Place Bound Bottom")
		(35 "F.Fab" user "Ref Des/Assembly Top")
		(33 "B.Fab" user "Ref Des/Assembly Bottom")
	)
	(footprint ""
		(layer "F.Cu")
		(at 54.598824 -8.584946)
		(property "Reference" "R7"
			(at 0 0 0)
			(layer "F.SilkS")
			(hide yes)
			(effects
				(font
					(size 1.27 1.27)
				)
			)
		)
		(property "Value" "10KR2J-3-GP"
			(at 0.064008 -3.993896 0)
			(unlocked yes)
			(layer "F.Fab")
			(hide yes)
			(effects
				(font
					(size 1.016 1.016)
					(thickness 0.1524)
				)
			)
		)
		(property "Device Type" "R402H16"
			(at 0.064008 -5.517896 0)
			(unlocked yes)
			(layer "F.Fab")
			(hide yes)
			(effects
				(font
					(size 1.016 1.016)
					(thickness 0.1524)
				)
			)
		)
		(duplicate_pad_numbers_are_jumpers no)
		(fp_line
			(start -0.508 -0.9398)
			(end -0.508 0.9398)
			(stroke
				(width 0.1524)
				(type default)
			)
			(layer "F.SilkS")
		)
		(fp_line
			(start 0.508 -0.9398)
			(end -0.508 -0.9398)
			(stroke
				(width 0.1524)
				(type default)
			)
			(layer "F.SilkS")
		)
		(fp_rect
			(start -0.508 0.9398)
			(end 0.508 -0.9398)
			(stroke
				(width 0)
				(type default)
			)
			(fill no)
			(layer "F.CrtYd")
		)
		(fp_rect
			(start -0.508 0.9398)
			(end 0.508 -0.9398)
			(stroke
				(width 0)
				(type default)
			)
			(fill no)
			(layer "F.Fab")
		)
		(pad "1" smd custom
			(at 0 -0.4445)
			(size 0.1397 0.1397)
			(layers "F.Cu" "F.Mask" "F.Paste")
			(net "P3V3")
			(options
				(clearance outline)
				(anchor circle)
			)
			(primitives
				(gr_poly
					(pts
						(arc
							(start -0.1778 -0.2794)
							(mid -0.249642 -0.249642)
							(end -0.2794 -0.1778)
						)
						(arc
							(start -0.2794 0.1778)
							(mid -0.249642 0.249642)
							(end -0.1778 0.2794)
						)
						(arc
							(start 0.1778 0.2794)
							(mid 0.249642 0.249642)
							(end 0.2794 0.1778)
						)
						(arc
							(start 0.2794 -0.1778)
							(mid 0.249642 -0.249642)
							(end 0.1778 -0.2794)
						)
					)
					(width 0)
					(fill yes)
				)
			)
		)
		(pad "2" smd custom
			(at 0 0.4445)
			(size 0.1397 0.1397)
			(layers "F.Cu" "F.Mask" "F.Paste")
			(net "HBA_PRSNT3_N")
			(options
				(clearance outline)
				(anchor circle)
			)
			(primitives
				(gr_poly
					(pts
						(arc
							(start -0.1778 -0.2794)
							(mid -0.249642 -0.249642)
							(end -0.2794 -0.1778)
						)
						(arc
							(start -0.2794 0.1778)
							(mid -0.249642 0.249642)
							(end -0.1778 0.2794)
						)
						(arc
							(start 0.1778 0.2794)
							(mid 0.249642 0.249642)
							(end 0.2794 0.1778)
						)
						(arc
							(start 0.2794 -0.1778)
							(mid 0.249642 -0.249642)
							(end 0.1778 -0.2794)
						)
					)
					(width 0)
					(fill yes)
				)
			)
		)
	)
	(footprint ""
		(layer "F.Cu")
		(at 11.811 -19.304 -90)
		(property "Reference" "C25"
			(at 0 0 270)
			(layer "F.SilkS")
			(hide yes)
			(effects
				(font
					(size 1.27 1.27)
				)
			)
		)
		(property "Value" "SCD1U25V2KX-GP"
			(at 1.1811 -2.7051 270)
			(unlocked yes)
			(layer "F.Fab")
			(hide yes)
			(effects
				(font
					(size 1.016 1.016)
					(thickness 0.1524)
				)
			)
		)
		(property "Device Type" "C402H22"
			(at 1.1811 -4.2291 270)
			(unlocked yes)
			(layer "F.Fab")
			(hide yes)
			(effects
				(font
					(size 1.016 1.016)
					(thickness 0.1524)
				)
			)
		)
		(duplicate_pad_numbers_are_jumpers no)
		(fp_rect
			(start -0.4318 0.9525)
			(end 0.4318 -0.9525)
			(stroke
				(width 0)
				(type default)
			)
			(fill no)
			(layer "F.CrtYd")
		)
		(fp_rect
			(start -0.4318 0.9525)
			(end 0.4318 -0.9525)
			(stroke
				(width 0)
				(type default)
			)
			(fill no)
			(layer "F.Fab")
		)
		(pad "1" smd custom
			(at 0 -0.4445 270)
			(size 0.1524 0.1524)
			(layers "F.Cu" "F.Mask" "F.Paste")
			(net "P5V")
			(options
				(clearance outline)
				(anchor circle)
			)
			(primitives
				(gr_poly
					(pts
						(arc
							(start 0.3048 -0.2032)
							(mid 0.275042 -0.275042)
							(end 0.2032 -0.3048)
						)
						(arc
							(start -0.2032 -0.3048)
							(mid -0.275042 -0.275042)
							(end -0.3048 -0.2032)
						)
						(arc
							(start -0.3048 0.2032)
							(mid -0.275042 0.275042)
							(end -0.2032 0.3048)
						)
						(arc
							(start 0.2032 0.3048)
							(mid 0.275042 0.275042)
							(end 0.3048 0.2032)
						)
					)
					(width 0)
					(fill yes)
				)
			)
		)
		(pad "2" smd custom
			(at 0 0.4445 270)
			(size 0.1524 0.1524)
			(layers "F.Cu" "F.Mask" "F.Paste")
			(net "GND")
			(options
				(clearance outline)
				(anchor circle)
			)
			(primitives
				(gr_poly
					(pts
						(arc
							(start 0.3048 -0.2032)
							(mid 0.275042 -0.275042)
							(end 0.2032 -0.3048)
						)
						(arc
							(start -0.2032 -0.3048)
							(mid -0.275042 -0.275042)
							(end -0.3048 -0.2032)
						)
						(arc
							(start -0.3048 0.2032)
							(mid -0.275042 0.275042)
							(end -0.2032 0.3048)
						)
						(arc
							(start 0.2032 0.3048)
							(mid 0.275042 0.275042)
							(end 0.3048 0.2032)
						)
					)
					(width 0)
					(fill yes)
				)
			)
		)
	)
	(footprint ""
		(layer "F.Cu")
		(at 75.0062 -40.3098 -90)
		(property "Reference" "C9"
			(at 0 0 270)
			(layer "F.SilkS")
			(hide yes)
			(effects
				(font
					(size 1.27 1.27)
				)
			)
		)
		(property "Value" "SC10U25V6KX-1GP"
			(at -0.0762 -5.1308 270)
			(unlocked yes)
			(layer "F.Fab")
			(hide yes)
			(effects
				(font
					(size 1.016 1.016)
					(thickness 0.1524)
				)
			)
		)
		(property "Device Type" "C1206H71"
			(at -0.127 -6.6548 270)
			(unlocked yes)
			(layer "F.Fab")
			(hide yes)
			(effects
				(font
					(size 1.016 1.016)
					(thickness 0.1524)
				)
			)
		)
		(duplicate_pad_numbers_are_jumpers no)
		(fp_line
			(start -1.016 2.2352)
			(end -1.016 0.8382)
			(stroke
				(width 0.1524)
				(type default)
			)
			(layer "F.SilkS")
		)
		(fp_line
			(start 1.016 2.2352)
			(end -1.016 2.2352)
			(stroke
				(width 0.1524)
				(type default)
			)
			(layer "F.SilkS")
		)
		(fp_line
			(start 1.016 0.8382)
			(end 1.016 2.2352)
			(stroke
				(width 0.1524)
				(type default)
			)
			(layer "F.SilkS")
		)
		(fp_line
			(start -1.016 -0.8382)
			(end -1.016 -2.2352)
			(stroke
				(width 0.1524)
				(type default)
			)
			(layer "F.SilkS")
		)
		(fp_line
			(start -1.016 -2.2352)
			(end 1.016 -2.2352)
			(stroke
				(width 0.1524)
				(type default)
			)
			(layer "F.SilkS")
		)
		(fp_line
			(start 1.016 -2.2352)
			(end 1.016 -0.8382)
			(stroke
				(width 0.1524)
				(type default)
			)
			(layer "F.SilkS")
		)
		(fp_rect
			(start -1.0922 2.3114)
			(end 1.0922 -2.3114)
			(stroke
				(width 0)
				(type default)
			)
			(fill no)
			(layer "F.CrtYd")
		)
		(fp_poly
			(pts
				(xy 1.0922 -2.3114) (xy 1.0922 2.3114) (xy -1.0922 2.3114) (xy -1.0922 -2.3114)
			)
			(stroke
				(width 0)
				(type default)
			)
			(fill no)
			(layer "F.Fab")
		)
		(pad "1" smd rect
			(at 0 -1.397 270)
			(size 1.651 1.27)
			(layers "F.Cu" "F.Mask" "F.Paste")
			(net "P12V_SW_R")
		)
		(pad "2" smd rect
			(at 0 1.397 270)
			(size 1.651 1.27)
			(layers "F.Cu" "F.Mask" "F.Paste")
			(net "GND")
		)
	)
	(footprint ""
		(layer "F.Cu")
		(at 124.841 -40.2082 -90)
		(property "Reference" "R3"
			(at 0 0 270)
			(layer "F.SilkS")
			(hide yes)
			(effects
				(font
					(size 1.27 1.27)
				)
			)
		)
		(property "Value" "10R3F-GP"
			(at -0.0254 -2.5146 270)
			(unlocked yes)
			(layer "F.Fab")
			(hide yes)
			(effects
				(font
					(size 1.016 1.016)
					(thickness 0.1524)
				)
			)
		)
		(property "Device Type" "R603H22"
			(at -0.0254 -4.0386 270)
			(unlocked yes)
			(layer "F.Fab")
			(hide yes)
			(effects
				(font
					(size 1.016 1.016)
					(thickness 0.1524)
				)
			)
		)
		(duplicate_pad_numbers_are_jumpers no)
		(fp_line
			(start -0.4826 0)
			(end -0.2032 0)
			(stroke
				(width 0.2032)
				(type default)
			)
			(layer "F.SilkS")
		)
		(fp_line
			(start 0.2032 0)
			(end 0.4826 0)
			(stroke
				(width 0.2032)
				(type default)
			)
			(layer "F.SilkS")
		)
		(fp_rect
			(start -0.5842 1.3335)
			(end 0.5842 -1.3335)
			(stroke
				(width 0)
				(type default)
			)
			(fill no)
			(layer "F.CrtYd")
		)
		(fp_rect
			(start -0.5842 1.3335)
			(end 0.5842 -1.3335)
			(stroke
				(width 0)
				(type default)
			)
			(fill no)
			(layer "F.Fab")
		)
		(pad "1" smd custom
			(at 0 -0.762 270)
			(size 0.2159 0.2159)
			(layers "F.Cu" "F.Mask" "F.Paste")
			(net "P5V_SW_R")
			(options
				(clearance outline)
				(anchor circle)
			)
			(primitives
				(gr_poly
					(pts
						(arc
							(start -0.3302 -0.4318)
							(mid -0.402042 -0.402042)
							(end -0.4318 -0.3302)
						)
						(arc
							(start -0.4318 0.3302)
							(mid -0.402042 0.402042)
							(end -0.3302 0.4318)
						)
						(arc
							(start 0.3302 0.4318)
							(mid 0.402042 0.402042)
							(end 0.4318 0.3302)
						)
						(arc
							(start 0.4318 -0.3302)
							(mid 0.402042 -0.402042)
							(end 0.3302 -0.4318)
						)
					)
					(width 0)
					(fill yes)
				)
			)
		)
		(pad "2" smd custom
			(at 0 0.762 270)
			(size 0.2159 0.2159)
			(layers "F.Cu" "F.Mask" "F.Paste")
			(net "5V_PRE_1")
			(options
				(clearance outline)
				(anchor circle)
			)
			(primitives
				(gr_poly
					(pts
						(arc
							(start -0.3302 -0.4318)
							(mid -0.402042 -0.402042)
							(end -0.4318 -0.3302)
						)
						(arc
							(start -0.4318 0.3302)
							(mid -0.402042 0.402042)
							(end -0.3302 0.4318)
						)
						(arc
							(start 0.3302 0.4318)
							(mid 0.402042 0.402042)
							(end 0.4318 0.3302)
						)
						(arc
							(start 0.4318 -0.3302)
							(mid 0.402042 -0.402042)
							(end 0.3302 -0.4318)
						)
					)
					(width 0)
					(fill yes)
				)
			)
		)
	)
	(footprint ""
		(layer "F.Cu")
		(at 53.721 -19.431)
		(property "Reference" "R8"
			(at 0 0 0)
			(layer "F.SilkS")
			(hide yes)
			(effects
				(font
					(size 1.27 1.27)
				)
			)
		)
		(property "Value" "10KR2J-3-GP"
			(at 0.064008 -3.993896 0)
			(unlocked yes)
			(layer "F.Fab")
			(hide yes)
			(effects
				(font
					(size 1.016 1.016)
					(thickness 0.1524)
				)
			)
		)
		(property "Device Type" "R402H16"
			(at 0.064008 -5.517896 0)
			(unlocked yes)
			(layer "F.Fab")
			(hide yes)
			(effects
				(font
					(size 1.016 1.016)
					(thickness 0.1524)
				)
			)
		)
		(duplicate_pad_numbers_are_jumpers no)
		(fp_line
			(start -0.508 -0.9398)
			(end -0.508 0.9398)
			(stroke
				(width 0.1524)
				(type default)
			)
			(layer "F.SilkS")
		)
		(fp_line
			(start 0.508 -0.9398)
			(end -0.508 -0.9398)
			(stroke
				(width 0.1524)
				(type default)
			)
			(layer "F.SilkS")
		)
		(fp_rect
			(start -0.508 0.9398)
			(end 0.508 -0.9398)
			(stroke
				(width 0)
				(type default)
			)
			(fill no)
			(layer "F.CrtYd")
		)
		(fp_rect
			(start -0.508 0.9398)
			(end 0.508 -0.9398)
			(stroke
				(width 0)
				(type default)
			)
			(fill no)
			(layer "F.Fab")
		)
		(pad "1" smd custom
			(at 0 -0.4445)
			(size 0.1397 0.1397)
			(layers "F.Cu" "F.Mask" "F.Paste")
			(net "P3V3")
			(options
				(clearance outline)
				(anchor circle)
			)
			(primitives
				(gr_poly
					(pts
						(arc
							(start -0.1778 -0.2794)
							(mid -0.249642 -0.249642)
							(end -0.2794 -0.1778)
						)
						(arc
							(start -0.2794 0.1778)
							(mid -0.249642 0.249642)
							(end -0.1778 0.2794)
						)
						(arc
							(start 0.1778 0.2794)
							(mid 0.249642 0.249642)
							(end 0.2794 0.1778)
						)
						(arc
							(start 0.2794 -0.1778)
							(mid 0.249642 -0.249642)
							(end 0.1778 -0.2794)
						)
					)
					(width 0)
					(fill yes)
				)
			)
		)
		(pad "2" smd custom
			(at 0 0.4445)
			(size 0.1397 0.1397)
			(layers "F.Cu" "F.Mask" "F.Paste")
			(net "HBA_PRSNT2_N")
			(options
				(clearance outline)
				(anchor circle)
			)
			(primitives
				(gr_poly
					(pts
						(arc
							(start -0.1778 -0.2794)
							(mid -0.249642 -0.249642)
							(end -0.2794 -0.1778)
						)
						(arc
							(start -0.2794 0.1778)
							(mid -0.249642 0.249642)
							(end -0.1778 0.2794)
						)
						(arc
							(start 0.1778 0.2794)
							(mid 0.249642 0.249642)
							(end 0.2794 0.1778)
						)
						(arc
							(start 0.2794 -0.1778)
							(mid 0.249642 -0.249642)
							(end 0.1778 -0.2794)
						)
					)
					(width 0)
					(fill yes)
				)
			)
		)
	)
	(footprint ""
		(layer "F.Cu")
		(at 51.428396 -9.891014 90)
		(property "Reference" "C18"
			(at 0 0 90)
			(layer "F.SilkS")
			(hide yes)
			(effects
				(font
					(size 1.27 1.27)
				)
			)
		)
		(property "Value" "SCD1U25V2KX-GP"
			(at 1.1811 -2.7051 90)
			(unlocked yes)
			(layer "F.Fab")
			(hide yes)
			(effects
				(font
					(size 1.016 1.016)
					(thickness 0.1524)
				)
			)
		)
		(property "Device Type" "C402H22"
			(at 1.1811 -4.2291 90)
			(unlocked yes)
			(layer "F.Fab")
			(hide yes)
			(effects
				(font
					(size 1.016 1.016)
					(thickness 0.1524)
				)
			)
		)
		(duplicate_pad_numbers_are_jumpers no)
		(fp_rect
			(start -0.4318 0.9525)
			(end 0.4318 -0.9525)
			(stroke
				(width 0)
				(type default)
			)
			(fill no)
			(layer "F.CrtYd")
		)
		(fp_rect
			(start -0.4318 0.9525)
			(end 0.4318 -0.9525)
			(stroke
				(width 0)
				(type default)
			)
			(fill no)
			(layer "F.Fab")
		)
		(pad "1" smd custom
			(at 0 -0.4445 90)
			(size 0.1524 0.1524)
			(layers "F.Cu" "F.Mask" "F.Paste")
			(net "P5V_SW_L")
			(options
				(clearance outline)
				(anchor circle)
			)
			(primitives
				(gr_poly
					(pts
						(arc
							(start 0.3048 -0.2032)
							(mid 0.275042 -0.275042)
							(end 0.2032 -0.3048)
						)
						(arc
							(start -0.2032 -0.3048)
							(mid -0.275042 -0.275042)
							(end -0.3048 -0.2032)
						)
						(arc
							(start -0.3048 0.2032)
							(mid -0.275042 0.275042)
							(end -0.2032 0.3048)
						)
						(arc
							(start 0.2032 0.3048)
							(mid 0.275042 0.275042)
							(end 0.3048 0.2032)
						)
					)
					(width 0)
					(fill yes)
				)
			)
		)
		(pad "2" smd custom
			(at 0 0.4445 90)
			(size 0.1524 0.1524)
			(layers "F.Cu" "F.Mask" "F.Paste")
			(net "GND")
			(options
				(clearance outline)
				(anchor circle)
			)
			(primitives
				(gr_poly
					(pts
						(arc
							(start 0.3048 -0.2032)
							(mid 0.275042 -0.275042)
							(end 0.2032 -0.3048)
						)
						(arc
							(start -0.2032 -0.3048)
							(mid -0.275042 -0.275042)
							(end -0.3048 -0.2032)
						)
						(arc
							(start -0.3048 0.2032)
							(mid -0.275042 0.275042)
							(end -0.2032 0.3048)
						)
						(arc
							(start 0.2032 0.3048)
							(mid 0.275042 0.275042)
							(end 0.3048 0.2032)
						)
					)
					(width 0)
					(fill yes)
				)
			)
		)
	)
	(footprint ""
		(layer "F.Cu")
		(at 125.640084 -56.909208 -90)
		(property "Reference" "R6"
			(at 0 0 270)
			(layer "F.SilkS")
			(hide yes)
			(effects
				(font
					(size 1.27 1.27)
				)
			)
		)
		(property "Value" "10R3F-GP"
			(at -0.0254 -2.5146 270)
			(unlocked yes)
			(layer "F.Fab")
			(hide yes)
			(effects
				(font
					(size 1.016 1.016)
					(thickness 0.1524)
				)
			)
		)
		(property "Device Type" "R603H22"
			(at -0.0254 -4.0386 270)
			(unlocked yes)
			(layer "F.Fab")
			(hide yes)
			(effects
				(font
					(size 1.016 1.016)
					(thickness 0.1524)
				)
			)
		)
		(duplicate_pad_numbers_are_jumpers no)
		(fp_line
			(start -0.4826 0)
			(end -0.2032 0)
			(stroke
				(width 0.2032)
				(type default)
			)
			(layer "F.SilkS")
		)
		(fp_line
			(start 0.2032 0)
			(end 0.4826 0)
			(stroke
				(width 0.2032)
				(type default)
			)
			(layer "F.SilkS")
		)
		(fp_rect
			(start -0.5842 1.3335)
			(end 0.5842 -1.3335)
			(stroke
				(width 0)
				(type default)
			)
			(fill no)
			(layer "F.CrtYd")
		)
		(fp_rect
			(start -0.5842 1.3335)
			(end 0.5842 -1.3335)
			(stroke
				(width 0)
				(type default)
			)
			(fill no)
			(layer "F.Fab")
		)
		(pad "1" smd custom
			(at 0 -0.762 270)
			(size 0.2159 0.2159)
			(layers "F.Cu" "F.Mask" "F.Paste")
			(net "P12V_SW_R")
			(options
				(clearance outline)
				(anchor circle)
			)
			(primitives
				(gr_poly
					(pts
						(arc
							(start -0.3302 -0.4318)
							(mid -0.402042 -0.402042)
							(end -0.4318 -0.3302)
						)
						(arc
							(start -0.4318 0.3302)
							(mid -0.402042 0.402042)
							(end -0.3302 0.4318)
						)
						(arc
							(start 0.3302 0.4318)
							(mid 0.402042 0.402042)
							(end 0.4318 0.3302)
						)
						(arc
							(start 0.4318 -0.3302)
							(mid 0.402042 -0.402042)
							(end 0.3302 -0.4318)
						)
					)
					(width 0)
					(fill yes)
				)
			)
		)
		(pad "2" smd custom
			(at 0 0.762 270)
			(size 0.2159 0.2159)
			(layers "F.Cu" "F.Mask" "F.Paste")
			(net "12V_PRE_0")
			(options
				(clearance outline)
				(anchor circle)
			)
			(primitives
				(gr_poly
					(pts
						(arc
							(start -0.3302 -0.4318)
							(mid -0.402042 -0.402042)
							(end -0.4318 -0.3302)
						)
						(arc
							(start -0.4318 0.3302)
							(mid -0.402042 0.402042)
							(end -0.3302 0.4318)
						)
						(arc
							(start 0.3302 0.4318)
							(mid 0.402042 0.402042)
							(end 0.4318 0.3302)
						)
						(arc
							(start 0.4318 -0.3302)
							(mid 0.402042 -0.402042)
							(end 0.3302 -0.4318)
						)
					)
					(width 0)
					(fill yes)
				)
			)
		)
	)
	(footprint ""
		(layer "F.Cu")
		(at 50.45202 -19.396456 90)
		(property "Reference" "C16"
			(at 0 0 90)
			(layer "F.SilkS")
			(hide yes)
			(effects
				(font
					(size 1.27 1.27)
				)
			)
		)
		(property "Value" "SC10U10V5KX-L1-GP"
			(at -0.0762 -6.1214 90)
			(unlocked yes)
			(layer "F.Fab")
			(hide yes)
			(effects
				(font
					(size 1.016 1.016)
					(thickness 0.1524)
				)
			)
		)
		(property "Device Type" "C805H58"
			(at -0.0762 -8.1534 90)
			(unlocked yes)
			(layer "F.Fab")
			(hide yes)
			(effects
				(font
					(size 1.016 1.016)
					(thickness 0.1524)
				)
			)
		)
		(duplicate_pad_numbers_are_jumpers no)
		(fp_line
			(start 0.635 0)
			(end -0.635 0)
			(stroke
				(width 0.508)
				(type default)
			)
			(layer "F.SilkS")
		)
		(fp_rect
			(start -0.9652 1.778)
			(end 0.9652 -1.778)
			(stroke
				(width 0)
				(type default)
			)
			(fill no)
			(layer "F.CrtYd")
		)
		(fp_poly
			(pts
				(xy -0.9652 -1.778) (xy 0.9652 -1.778) (xy 0.9652 1.778) (xy -0.9652 1.778)
			)
			(stroke
				(width 0)
				(type default)
			)
			(fill no)
			(layer "F.Fab")
		)
		(pad "1" smd rect
			(at 0 -0.9652 90)
			(size 1.397 1.143)
			(layers "F.Cu" "F.Mask" "F.Paste")
			(net "P5V_SW_L")
		)
		(pad "2" smd rect
			(at 0 0.9652 90)
			(size 1.397 1.143)
			(layers "F.Cu" "F.Mask" "F.Paste")
			(net "GND")
		)
	)
)
